(kicad_pcb
	(version 20260206)
	(generator "pcbnew")
	(generator_version "10.0")
	(general
		(thickness 1.6)
		(legacy_teardrops no)
	)
	(paper "A4")
	(title_block
		(title "Bryce Canyon_SCC_16316-1_OCP.brd")
		(comment 1 "Bryce Canyon / footprints 1544-1550 of 1561")
	)
	(layers
		(0 "F.Cu" signal "TOP")
		(4 "In1.Cu" signal "L2GND")
		(6 "In2.Cu" signal "L3")
		(8 "In3.Cu" signal "L4VCC")
		(10 "In4.Cu" signal "L5VCC")
		(12 "In5.Cu" signal "L6")
		(14 "In6.Cu" signal "L7GND")
		(2 "B.Cu" signal "BOTTOM")
		(9 "F.Adhes" user "F.Adhesive")
		(11 "B.Adhes" user "B.Adhesive")
		(13 "F.Paste" user "Package Geometry/Pastemask Top")
		(15 "B.Paste" user "Package Geometry/Pastemask Bottom")
		(5 "F.SilkS" user "Ref Des/Silkscreen Top")
		(7 "B.SilkS" user "Ref Des/Silkscreen Bottom")
		(1 "F.Mask" user "Board Geometry/Soldermask Top")
		(3 "B.Mask" user "Board Geometry/Soldermask Bottom")
		(17 "Dwgs.User" user "User.Drawings")
		(19 "Cmts.User" user "User.Comments")
		(21 "Eco1.User" user "User.Eco1")
		(23 "Eco2.User" user "User.Eco2")
		(25 "Edge.Cuts" user "Board Geometry/Outline")
		(27 "Margin" user)
		(31 "F.CrtYd" user "Package Geometry/Place Bound Top")
		(29 "B.CrtYd" user "Package Geometry/Place Bound Bottom")
		(35 "F.Fab" user "Ref Des/Assembly Top")
		(33 "B.Fab" user "Ref Des/Assembly Bottom")
	)
	(footprint ""
		(layer "B.Cu")
		(at 94.843092 -86.63178 -90)
		(property "Reference" "R135"
			(at 0 0 90)
			(layer "B.SilkS")
			(hide yes)
			(effects
				(font
					(size 1.27 1.27)
				)
				(justify mirror)
			)
		)
		(property "Value" "4K7R2F-GP"
			(at -0.064008 -3.993896 270)
			(unlocked yes)
			(layer "B.Fab")
			(hide yes)
			(effects
				(font
					(size 1.016 1.016)
					(thickness 0.1524)
				)
				(justify mirror)
			)
		)
		(property "Device Type" "R402H16"
			(at -0.064008 -5.517896 270)
			(unlocked yes)
			(layer "B.Fab")
			(hide yes)
			(effects
				(font
					(size 1.016 1.016)
					(thickness 0.1524)
				)
				(justify mirror)
			)
		)
		(duplicate_pad_numbers_are_jumpers no)
		(fp_line
			(start -0.508 -0.9398)
			(end 0.508 -0.9398)
			(stroke
				(width 0.1524)
				(type default)
			)
			(layer "B.SilkS")
		)
		(fp_line
			(start 0.508 -0.9398)
			(end 0.508 0.9398)
			(stroke
				(width 0.1524)
				(type default)
			)
			(layer "B.SilkS")
		)
		(fp_rect
			(start 0.508 0.9398)
			(end -0.508 -0.9398)
			(stroke
				(width 0)
				(type default)
			)
			(fill no)
			(layer "B.CrtYd")
		)
		(fp_rect
			(start 0.508 0.9398)
			(end -0.508 -0.9398)
			(stroke
				(width 0)
				(type default)
			)
			(fill no)
			(layer "B.Fab")
		)
		(pad "1" smd custom
			(at 0 -0.4445 90)
			(size 0.1397 0.1397)
			(layers "B.Cu" "B.Mask" "B.Paste")
			(net "P1V8_E")
			(options
				(clearance outline)
				(anchor circle)
			)
			(primitives
				(gr_poly
					(pts
						(arc
							(start -0.1778 0.2794)
							(mid -0.249642 0.249642)
							(end -0.2794 0.1778)
						)
						(arc
							(start -0.2794 -0.1778)
							(mid -0.249642 -0.249642)
							(end -0.1778 -0.2794)
						)
						(arc
							(start 0.1778 -0.2794)
							(mid 0.249642 -0.249642)
							(end 0.2794 -0.1778)
						)
						(arc
							(start 0.2794 0.1778)
							(mid 0.249642 0.249642)
							(end 0.1778 0.2794)
						)
					)
					(width 0)
					(fill yes)
				)
			)
		)
		(pad "2" smd custom
			(at 0 0.4445 90)
			(size 0.1397 0.1397)
			(layers "B.Cu" "B.Mask" "B.Paste")
			(net "ICE_RESET_N")
			(options
				(clearance outline)
				(anchor circle)
			)
			(primitives
				(gr_poly
					(pts
						(arc
							(start -0.1778 0.2794)
							(mid -0.249642 0.249642)
							(end -0.2794 0.1778)
						)
						(arc
							(start -0.2794 -0.1778)
							(mid -0.249642 -0.249642)
							(end -0.1778 -0.2794)
						)
						(arc
							(start 0.1778 -0.2794)
							(mid 0.249642 -0.249642)
							(end 0.2794 -0.1778)
						)
						(arc
							(start 0.2794 0.1778)
							(mid 0.249642 0.249642)
							(end 0.1778 0.2794)
						)
					)
					(width 0)
					(fill yes)
				)
			)
		)
	)
	(footprint ""
		(layer "B.Cu")
		(at 113.411 -44.2214 180)
		(property "Reference" "C66"
			(at 0 0 0)
			(layer "B.SilkS")
			(hide yes)
			(effects
				(font
					(size 1.27 1.27)
				)
				(justify mirror)
			)
		)
		(property "Value" "SCD01U16V1KX-GP"
			(at 2.8321 -1.7399 180)
			(unlocked yes)
			(layer "B.Fab")
			(hide yes)
			(effects
				(font
					(size 1.016 1.016)
					(thickness 0.1524)
				)
				(justify mirror)
			)
		)
		(property "Device Type" "C0201H13"
			(at 2.8321 -3.2639 180)
			(unlocked yes)
			(layer "B.Fab")
			(hide yes)
			(effects
				(font
					(size 1.016 1.016)
					(thickness 0.1524)
				)
				(justify mirror)
			)
		)
		(duplicate_pad_numbers_are_jumpers no)
		(fp_rect
			(start 0.2794 0.6477)
			(end -0.2794 -0.6477)
			(stroke
				(width 0)
				(type default)
			)
			(fill no)
			(layer "B.CrtYd")
		)
		(fp_rect
			(start 0.2794 0.6477)
			(end -0.2794 -0.6477)
			(stroke
				(width 0)
				(type default)
			)
			(fill no)
			(layer "B.Fab")
		)
		(pad "1" smd custom
			(at 0 -0.2794)
			(size 0.0762 0.0762)
			(layers "B.Cu" "B.Mask" "B.Paste")
			(net "PHY_DPB_TO_SCC_27_DN")
			(options
				(clearance outline)
				(anchor circle)
			)
			(primitives
				(gr_poly
					(pts
						(arc
							(start 0.1524 0.127)
							(mid 0.137521 0.162921)
							(end 0.1016 0.1778)
						)
						(arc
							(start -0.1016 0.1778)
							(mid -0.137521 0.162921)
							(end -0.1524 0.127)
						)
						(arc
							(start -0.1524 -0.127)
							(mid -0.137521 -0.162921)
							(end -0.1016 -0.1778)
						)
						(arc
							(start 0.1016 -0.1778)
							(mid 0.137521 -0.162921)
							(end 0.1524 -0.127)
						)
					)
					(width 0)
					(fill yes)
				)
			)
		)
		(pad "2" smd custom
			(at 0 0.2794)
			(size 0.0762 0.0762)
			(layers "B.Cu" "B.Mask" "B.Paste")
			(net "PHY_DPB_TO_SCC_C_27_DN")
			(options
				(clearance outline)
				(anchor circle)
			)
			(primitives
				(gr_poly
					(pts
						(arc
							(start 0.1524 0.127)
							(mid 0.137521 0.162921)
							(end 0.1016 0.1778)
						)
						(arc
							(start -0.1016 0.1778)
							(mid -0.137521 0.162921)
							(end -0.1524 0.127)
						)
						(arc
							(start -0.1524 -0.127)
							(mid -0.137521 -0.162921)
							(end -0.1016 -0.1778)
						)
						(arc
							(start 0.1016 -0.1778)
							(mid 0.137521 -0.162921)
							(end 0.1524 -0.127)
						)
					)
					(width 0)
					(fill yes)
				)
			)
		)
	)
	(footprint ""
		(layer "B.Cu")
		(at 183.144668 -46.42993 -90)
		(property "Reference" "C480"
			(at 0 0 90)
			(layer "B.SilkS")
			(hide yes)
			(effects
				(font
					(size 1.27 1.27)
				)
				(justify mirror)
			)
		)
		(property "Value" "SCD1U6D3V1KX-GP"
			(at 2.8321 -1.7399 270)
			(unlocked yes)
			(layer "B.Fab")
			(hide yes)
			(effects
				(font
					(size 1.016 1.016)
					(thickness 0.1524)
				)
				(justify mirror)
			)
		)
		(property "Device Type" "C0201H13"
			(at 2.8321 -3.2639 270)
			(unlocked yes)
			(layer "B.Fab")
			(hide yes)
			(effects
				(font
					(size 1.016 1.016)
					(thickness 0.1524)
				)
				(justify mirror)
			)
		)
		(duplicate_pad_numbers_are_jumpers no)
		(fp_rect
			(start 0.2794 0.6477)
			(end -0.2794 -0.6477)
			(stroke
				(width 0)
				(type default)
			)
			(fill no)
			(layer "B.CrtYd")
		)
		(fp_rect
			(start 0.2794 0.6477)
			(end -0.2794 -0.6477)
			(stroke
				(width 0)
				(type default)
			)
			(fill no)
			(layer "B.Fab")
		)
		(pad "1" smd custom
			(at 0 -0.2794 90)
			(size 0.0762 0.0762)
			(layers "B.Cu" "B.Mask" "B.Paste")
			(net "P1V8_C")
			(options
				(clearance outline)
				(anchor circle)
			)
			(primitives
				(gr_poly
					(pts
						(arc
							(start 0.1524 0.127)
							(mid 0.137521 0.162921)
							(end 0.1016 0.1778)
						)
						(arc
							(start -0.1016 0.1778)
							(mid -0.137521 0.162921)
							(end -0.1524 0.127)
						)
						(arc
							(start -0.1524 -0.127)
							(mid -0.137521 -0.162921)
							(end -0.1016 -0.1778)
						)
						(arc
							(start 0.1016 -0.1778)
							(mid 0.137521 -0.162921)
							(end 0.1524 -0.127)
						)
					)
					(width 0)
					(fill yes)
				)
			)
		)
		(pad "2" smd custom
			(at 0 0.2794 90)
			(size 0.0762 0.0762)
			(layers "B.Cu" "B.Mask" "B.Paste")
			(net "GND")
			(options
				(clearance outline)
				(anchor circle)
			)
			(primitives
				(gr_poly
					(pts
						(arc
							(start 0.1524 0.127)
							(mid 0.137521 0.162921)
							(end 0.1016 0.1778)
						)
						(arc
							(start -0.1016 0.1778)
							(mid -0.137521 0.162921)
							(end -0.1524 0.127)
						)
						(arc
							(start -0.1524 -0.127)
							(mid -0.137521 -0.162921)
							(end -0.1016 -0.1778)
						)
						(arc
							(start 0.1016 -0.1778)
							(mid 0.137521 -0.162921)
							(end 0.1524 -0.127)
						)
					)
					(width 0)
					(fill yes)
				)
			)
		)
	)
	(footprint ""
		(layer "B.Cu")
		(at 164.973 -31.9659 -90)
		(property "Reference" "C396"
			(at 0 0 90)
			(layer "B.SilkS")
			(hide yes)
			(effects
				(font
					(size 1.27 1.27)
				)
				(justify mirror)
			)
		)
		(property "Value" "SC1U16V2KX-7-GP"
			(at -1.7526 -1.6002 270)
			(unlocked yes)
			(layer "B.Fab")
			(hide yes)
			(effects
				(font
					(size 1.016 1.016)
					(thickness 0.1524)
				)
				(justify mirror)
			)
		)
		(property "Device Type" "C402-TO0D2H24"
			(at -1.7526 -3.1242 270)
			(unlocked yes)
			(layer "B.Fab")
			(hide yes)
			(effects
				(font
					(size 1.016 1.016)
					(thickness 0.1524)
				)
				(justify mirror)
			)
		)
		(duplicate_pad_numbers_are_jumpers no)
		(fp_rect
			(start 0.4826 0.889)
			(end -0.4826 -0.889)
			(stroke
				(width 0)
				(type default)
			)
			(fill no)
			(layer "B.CrtYd")
		)
		(fp_rect
			(start 0.4826 0.889)
			(end -0.4826 -0.889)
			(stroke
				(width 0)
				(type default)
			)
			(fill no)
			(layer "B.Fab")
		)
		(pad "1" smd custom
			(at 0 -0.4572 90)
			(size 0.1524 0.1524)
			(layers "B.Cu" "B.Mask" "B.Paste")
			(net "SAS0_AVDD")
			(options
				(clearance outline)
				(anchor circle)
			)
			(primitives
				(gr_poly
					(pts
						(arc
							(start -0.254 -0.3048)
							(mid -0.325842 -0.275042)
							(end -0.3556 -0.2032)
						)
						(arc
							(start -0.3556 0.2032)
							(mid -0.325842 0.275042)
							(end -0.254 0.3048)
						)
						(arc
							(start 0.254 0.3048)
							(mid 0.325842 0.275042)
							(end 0.3556 0.2032)
						)
						(arc
							(start 0.3556 -0.2032)
							(mid 0.325842 -0.275042)
							(end 0.254 -0.3048)
						)
					)
					(width 0)
					(fill yes)
				)
			)
		)
		(pad "2" smd custom
			(at 0 0.4572 90)
			(size 0.1524 0.1524)
			(layers "B.Cu" "B.Mask" "B.Paste")
			(net "GND")
			(options
				(clearance outline)
				(anchor circle)
			)
			(primitives
				(gr_poly
					(pts
						(arc
							(start -0.254 -0.3048)
							(mid -0.325842 -0.275042)
							(end -0.3556 -0.2032)
						)
						(arc
							(start -0.3556 0.2032)
							(mid -0.325842 0.275042)
							(end -0.254 0.3048)
						)
						(arc
							(start 0.254 0.3048)
							(mid 0.325842 0.275042)
							(end 0.3556 0.2032)
						)
						(arc
							(start 0.3556 -0.2032)
							(mid 0.325842 -0.275042)
							(end 0.254 -0.3048)
						)
					)
					(width 0)
					(fill yes)
				)
			)
		)
	)
	(footprint ""
		(layer "B.Cu")
		(at 103.505 -64.77 180)
		(property "Reference" "C198"
			(at 0 0 0)
			(layer "B.SilkS")
			(hide yes)
			(effects
				(font
					(size 1.27 1.27)
				)
				(justify mirror)
			)
		)
		(property "Value" "SC1U6D3V1MX-GP"
			(at -1.9177 2.0193 180)
			(unlocked yes)
			(layer "B.Fab")
			(hide yes)
			(effects
				(font
					(size 1.016 1.016)
					(thickness 0.1524)
				)
				(justify mirror)
			)
		)
		(property "Device Type" "C0201H14"
			(at -1.9177 0.4953 180)
			(unlocked yes)
			(layer "B.Fab")
			(hide yes)
			(effects
				(font
					(size 1.016 1.016)
					(thickness 0.1524)
				)
				(justify mirror)
			)
		)
		(duplicate_pad_numbers_are_jumpers no)
		(fp_rect
			(start 0.1524 0.3048)
			(end -0.1524 -0.3048)
			(stroke
				(width 0)
				(type default)
			)
			(fill no)
			(layer "B.CrtYd")
		)
		(fp_poly
			(pts
				(xy 0.2794 0.6477) (xy 0.2794 -0.6477) (xy -0.2794 -0.6477) (xy -0.2794 -0.1905) (xy -0.1524 -0.1905)
				(xy -0.1524 -0.3048) (xy 0.1524 -0.3048) (xy 0.1524 0.3048) (xy -0.1524 0.3048) (xy -0.1524 -0.1778)
				(xy -0.2794 -0.1778) (xy -0.2794 0.6477)
			)
			(stroke
				(width 0)
				(type default)
			)
			(fill no)
			(layer "B.CrtYd")
		)
		(fp_rect
			(start 0.2794 0.6477)
			(end -0.2794 -0.6477)
			(stroke
				(width 0)
				(type default)
			)
			(fill no)
			(layer "B.Fab")
		)
		(pad "1" smd custom
			(at 0 -0.2794)
			(size 0.0762 0.0762)
			(layers "B.Cu" "B.Mask" "B.Paste")
			(net "SYSPLL_VDDA18")
			(options
				(clearance outline)
				(anchor circle)
			)
			(primitives
				(gr_poly
					(pts
						(arc
							(start 0.1524 0.127)
							(mid 0.137521 0.162921)
							(end 0.1016 0.1778)
						)
						(arc
							(start -0.1016 0.1778)
							(mid -0.137521 0.162921)
							(end -0.1524 0.127)
						)
						(arc
							(start -0.1524 -0.127)
							(mid -0.137521 -0.162921)
							(end -0.1016 -0.1778)
						)
						(arc
							(start 0.1016 -0.1778)
							(mid 0.137521 -0.162921)
							(end 0.1524 -0.127)
						)
					)
					(width 0)
					(fill yes)
				)
			)
		)
		(pad "2" smd custom
			(at 0 0.2794)
			(size 0.0762 0.0762)
			(layers "B.Cu" "B.Mask" "B.Paste")
			(net "GND")
			(options
				(clearance outline)
				(anchor circle)
			)
			(primitives
				(gr_poly
					(pts
						(arc
							(start 0.1524 0.127)
							(mid 0.137521 0.162921)
							(end 0.1016 0.1778)
						)
						(arc
							(start -0.1016 0.1778)
							(mid -0.137521 0.162921)
							(end -0.1524 0.127)
						)
						(arc
							(start -0.1524 -0.127)
							(mid -0.137521 -0.162921)
							(end -0.1016 -0.1778)
						)
						(arc
							(start 0.1016 -0.1778)
							(mid 0.137521 -0.162921)
							(end 0.1524 -0.127)
						)
					)
					(width 0)
					(fill yes)
				)
			)
		)
	)
	(footprint ""
		(layer "B.Cu")
		(at 127.970788 -58.493914 -90)
		(property "Reference" "C309"
			(at 0 0 90)
			(layer "B.SilkS")
			(hide yes)
			(effects
				(font
					(size 1.27 1.27)
				)
				(justify mirror)
			)
		)
		(property "Value" "SC1U6D3V1MX-GP"
			(at -1.9177 2.0193 270)
			(unlocked yes)
			(layer "B.Fab")
			(hide yes)
			(effects
				(font
					(size 1.016 1.016)
					(thickness 0.1524)
				)
				(justify mirror)
			)
		)
		(property "Device Type" "C0201H14"
			(at -1.9177 0.4953 270)
			(unlocked yes)
			(layer "B.Fab")
			(hide yes)
			(effects
				(font
					(size 1.016 1.016)
					(thickness 0.1524)
				)
				(justify mirror)
			)
		)
		(duplicate_pad_numbers_are_jumpers no)
		(fp_rect
			(start 0.1524 0.3048)
			(end -0.1524 -0.3048)
			(stroke
				(width 0)
				(type default)
			)
			(fill no)
			(layer "B.CrtYd")
		)
		(fp_poly
			(pts
				(xy 0.2794 0.6477) (xy 0.2794 -0.6477) (xy -0.2794 -0.6477) (xy -0.2794 -0.1905) (xy -0.1524 -0.1905)
				(xy -0.1524 -0.3048) (xy 0.1524 -0.3048) (xy 0.1524 0.3048) (xy -0.1524 0.3048) (xy -0.1524 -0.1778)
				(xy -0.2794 -0.1778) (xy -0.2794 0.6477)
			)
			(stroke
				(width 0)
				(type default)
			)
			(fill no)
			(layer "B.CrtYd")
		)
		(fp_rect
			(start 0.2794 0.6477)
			(end -0.2794 -0.6477)
			(stroke
				(width 0)
				(type default)
			)
			(fill no)
			(layer "B.Fab")
		)
		(pad "1" smd custom
			(at 0 -0.2794 90)
			(size 0.0762 0.0762)
			(layers "B.Cu" "B.Mask" "B.Paste")
			(net "GB_VDDA")
			(options
				(clearance outline)
				(anchor circle)
			)
			(primitives
				(gr_poly
					(pts
						(arc
							(start 0.1524 0.127)
							(mid 0.137521 0.162921)
							(end 0.1016 0.1778)
						)
						(arc
							(start -0.1016 0.1778)
							(mid -0.137521 0.162921)
							(end -0.1524 0.127)
						)
						(arc
							(start -0.1524 -0.127)
							(mid -0.137521 -0.162921)
							(end -0.1016 -0.1778)
						)
						(arc
							(start 0.1016 -0.1778)
							(mid 0.137521 -0.162921)
							(end 0.1524 -0.127)
						)
					)
					(width 0)
					(fill yes)
				)
			)
		)
		(pad "2" smd custom
			(at 0 0.2794 90)
			(size 0.0762 0.0762)
			(layers "B.Cu" "B.Mask" "B.Paste")
			(net "GND")
			(options
				(clearance outline)
				(anchor circle)
			)
			(primitives
				(gr_poly
					(pts
						(arc
							(start 0.1524 0.127)
							(mid 0.137521 0.162921)
							(end 0.1016 0.1778)
						)
						(arc
							(start -0.1016 0.1778)
							(mid -0.137521 0.162921)
							(end -0.1524 0.127)
						)
						(arc
							(start -0.1524 -0.127)
							(mid -0.137521 -0.162921)
							(end -0.1016 -0.1778)
						)
						(arc
							(start 0.1016 -0.1778)
							(mid 0.137521 -0.162921)
							(end 0.1524 -0.127)
						)
					)
					(width 0)
					(fill yes)
				)
			)
		)
	)
	(footprint ""
		(layer "B.Cu")
		(at 114.8207 -66.3575)
		(property "Reference" "C162"
			(at 0 0 0)
			(layer "B.SilkS")
			(hide yes)
			(effects
				(font
					(size 1.27 1.27)
				)
				(justify mirror)
			)
		)
		(property "Value" "SCD1U6D3V1KX-GP"
			(at 2.8321 -1.7399 0)
			(unlocked yes)
			(layer "B.Fab")
			(hide yes)
			(effects
				(font
					(size 1.016 1.016)
					(thickness 0.1524)
				)
				(justify mirror)
			)
		)
		(property "Device Type" "C0201H13"
			(at 2.8321 -3.2639 0)
			(unlocked yes)
			(layer "B.Fab")
			(hide yes)
			(effects
				(font
					(size 1.016 1.016)
					(thickness 0.1524)
				)
				(justify mirror)
			)
		)
		(duplicate_pad_numbers_are_jumpers no)
		(fp_rect
			(start 0.2794 0.6477)
			(end -0.2794 -0.6477)
			(stroke
				(width 0)
				(type default)
			)
			(fill no)
			(layer "B.CrtYd")
		)
		(fp_rect
			(start 0.2794 0.6477)
			(end -0.2794 -0.6477)
			(stroke
				(width 0)
				(type default)
			)
			(fill no)
			(layer "B.Fab")
		)
		(pad "1" smd custom
			(at 0 -0.2794 180)
			(size 0.0762 0.0762)
			(layers "B.Cu" "B.Mask" "B.Paste")
			(net "P0V9")
			(options
				(clearance outline)
				(anchor circle)
			)
			(primitives
				(gr_poly
					(pts
						(arc
							(start 0.1524 0.127)
							(mid 0.137521 0.162921)
							(end 0.1016 0.1778)
						)
						(arc
							(start -0.1016 0.1778)
							(mid -0.137521 0.162921)
							(end -0.1524 0.127)
						)
						(arc
							(start -0.1524 -0.127)
							(mid -0.137521 -0.162921)
							(end -0.1016 -0.1778)
						)
						(arc
							(start 0.1016 -0.1778)
							(mid 0.137521 -0.162921)
							(end 0.1524 -0.127)
						)
					)
					(width 0)
					(fill yes)
				)
			)
		)
		(pad "2" smd custom
			(at 0 0.2794 180)
			(size 0.0762 0.0762)
			(layers "B.Cu" "B.Mask" "B.Paste")
			(net "GND")
			(options
				(clearance outline)
				(anchor circle)
			)
			(primitives
				(gr_poly
					(pts
						(arc
							(start 0.1524 0.127)
							(mid 0.137521 0.162921)
							(end 0.1016 0.1778)
						)
						(arc
							(start -0.1016 0.1778)
							(mid -0.137521 0.162921)
							(end -0.1524 0.127)
						)
						(arc
							(start -0.1524 -0.127)
							(mid -0.137521 -0.162921)
							(end -0.1016 -0.1778)
						)
						(arc
							(start 0.1016 -0.1778)
							(mid 0.137521 -0.162921)
							(end 0.1524 -0.127)
						)
					)
					(width 0)
					(fill yes)
				)
			)
		)
	)
)
